(kicad_pcb
	(version 20260206)
	(generator "pcbnew")
	(generator_version "10.0")
	(general
		(thickness 1.6)
		(legacy_teardrops no)
	)
	(paper "A4")
	(title_block
		(title "Bryce Canyon_R.DPB_16317-1_OCP.brd")
		(comment 1 "Bryce Canyon / footprints 990-996 of 2099")
	)
	(layers
		(0 "F.Cu" signal "TOP")
		(4 "In1.Cu" signal "L2GND")
		(6 "In2.Cu" signal "L3")
		(8 "In3.Cu" signal "L4VCC")
		(10 "In4.Cu" signal "L5VCC")
		(12 "In5.Cu" signal "L6")
		(14 "In6.Cu" signal "L7GND")
		(2 "B.Cu" signal "BOTTOM")
		(9 "F.Adhes" user "F.Adhesive")
		(11 "B.Adhes" user "B.Adhesive")
		(13 "F.Paste" user "Package Geometry/Pastemask Top")
		(15 "B.Paste" user "Package Geometry/Pastemask Bottom")
		(5 "F.SilkS" user "Ref Des/Silkscreen Top")
		(7 "B.SilkS" user "Ref Des/Silkscreen Bottom")
		(1 "F.Mask" user "Board Geometry/Soldermask Top")
		(3 "B.Mask" user "Board Geometry/Soldermask Bottom")
		(17 "Dwgs.User" user "User.Drawings")
		(19 "Cmts.User" user "User.Comments")
		(21 "Eco1.User" user "User.Eco1")
		(23 "Eco2.User" user "User.Eco2")
		(25 "Edge.Cuts" user "Board Geometry/Outline")
		(27 "Margin" user)
		(31 "F.CrtYd" user "Package Geometry/Place Bound Top")
		(29 "B.CrtYd" user "Package Geometry/Place Bound Bottom")
		(35 "F.Fab" user "Ref Des/Assembly Top")
		(33 "B.Fab" user "Ref Des/Assembly Bottom")
	)
	(footprint ""
		(layer "F.Cu")
		(at 35.687 -32.7914 180)
		(property "Reference" "R626"
			(at 0 0 180)
			(layer "F.SilkS")
			(hide yes)
			(effects
				(font
					(size 1.27 1.27)
				)
			)
		)
		(property "Value" "220R3F-1-GP"
			(at -0.0254 -2.5146 180)
			(unlocked yes)
			(layer "F.Fab")
			(hide yes)
			(effects
				(font
					(size 1.016 1.016)
					(thickness 0.1524)
				)
			)
		)
		(property "Device Type" "R603H22"
			(at -0.0254 -4.0386 180)
			(unlocked yes)
			(layer "F.Fab")
			(hide yes)
			(effects
				(font
					(size 1.016 1.016)
					(thickness 0.1524)
				)
			)
		)
		(duplicate_pad_numbers_are_jumpers no)
		(fp_line
			(start 0.2032 0)
			(end 0.4826 0)
			(stroke
				(width 0.2032)
				(type default)
			)
			(layer "F.SilkS")
		)
		(fp_line
			(start -0.4826 0)
			(end -0.2032 0)
			(stroke
				(width 0.2032)
				(type default)
			)
			(layer "F.SilkS")
		)
		(fp_rect
			(start -0.5842 1.3335)
			(end 0.5842 -1.3335)
			(stroke
				(width 0)
				(type default)
			)
			(fill no)
			(layer "F.CrtYd")
		)
		(fp_rect
			(start -0.5842 1.3335)
			(end 0.5842 -1.3335)
			(stroke
				(width 0)
				(type default)
			)
			(fill no)
			(layer "F.Fab")
		)
		(pad "1" smd custom
			(at 0 -0.762 180)
			(size 0.2159 0.2159)
			(layers "F.Cu" "F.Mask" "F.Paste")
			(net "HDD_PRSNT_24")
			(options
				(clearance outline)
				(anchor circle)
			)
			(primitives
				(gr_poly
					(pts
						(arc
							(start -0.3302 -0.4318)
							(mid -0.402042 -0.402042)
							(end -0.4318 -0.3302)
						)
						(arc
							(start -0.4318 0.3302)
							(mid -0.402042 0.402042)
							(end -0.3302 0.4318)
						)
						(arc
							(start 0.3302 0.4318)
							(mid 0.402042 0.402042)
							(end 0.4318 0.3302)
						)
						(arc
							(start 0.4318 -0.3302)
							(mid 0.402042 -0.402042)
							(end 0.3302 -0.4318)
						)
					)
					(width 0)
					(fill yes)
				)
			)
		)
		(pad "2" smd custom
			(at 0 0.762 180)
			(size 0.2159 0.2159)
			(layers "F.Cu" "F.Mask" "F.Paste")
			(net "DRIVE_B_24_INS")
			(options
				(clearance outline)
				(anchor circle)
			)
			(primitives
				(gr_poly
					(pts
						(arc
							(start -0.3302 -0.4318)
							(mid -0.402042 -0.402042)
							(end -0.4318 -0.3302)
						)
						(arc
							(start -0.4318 0.3302)
							(mid -0.402042 0.402042)
							(end -0.3302 0.4318)
						)
						(arc
							(start 0.3302 0.4318)
							(mid 0.402042 0.402042)
							(end 0.4318 0.3302)
						)
						(arc
							(start 0.4318 -0.3302)
							(mid 0.402042 -0.402042)
							(end 0.3302 -0.4318)
						)
					)
					(width 0)
					(fill yes)
				)
			)
		)
	)
	(footprint ""
		(layer "F.Cu")
		(at 470.193878 -217.413586 -90)
		(property "Reference" "R322"
			(at 0 0 270)
			(layer "F.SilkS")
			(hide yes)
			(effects
				(font
					(size 1.27 1.27)
				)
			)
		)
		(property "Value" "4K7R2F-GP"
			(at 0.064008 -3.993896 270)
			(unlocked yes)
			(layer "F.Fab")
			(hide yes)
			(effects
				(font
					(size 1.016 1.016)
					(thickness 0.1524)
				)
			)
		)
		(property "Device Type" "R402H16"
			(at 0.064008 -5.517896 270)
			(unlocked yes)
			(layer "F.Fab")
			(hide yes)
			(effects
				(font
					(size 1.016 1.016)
					(thickness 0.1524)
				)
			)
		)
		(duplicate_pad_numbers_are_jumpers no)
		(fp_line
			(start -0.508 -0.9398)
			(end -0.508 0.9398)
			(stroke
				(width 0.1524)
				(type default)
			)
			(layer "F.SilkS")
		)
		(fp_line
			(start 0.508 -0.9398)
			(end -0.508 -0.9398)
			(stroke
				(width 0.1524)
				(type default)
			)
			(layer "F.SilkS")
		)
		(fp_rect
			(start -0.508 0.9398)
			(end 0.508 -0.9398)
			(stroke
				(width 0)
				(type default)
			)
			(fill no)
			(layer "F.CrtYd")
		)
		(fp_rect
			(start -0.508 0.9398)
			(end 0.508 -0.9398)
			(stroke
				(width 0)
				(type default)
			)
			(fill no)
			(layer "F.Fab")
		)
		(pad "1" smd custom
			(at 0 -0.4445 270)
			(size 0.1397 0.1397)
			(layers "F.Cu" "F.Mask" "F.Paste")
			(net "DRIVE_B_11_FLT_LED")
			(options
				(clearance outline)
				(anchor circle)
			)
			(primitives
				(gr_poly
					(pts
						(arc
							(start -0.1778 -0.2794)
							(mid -0.249642 -0.249642)
							(end -0.2794 -0.1778)
						)
						(arc
							(start -0.2794 0.1778)
							(mid -0.249642 0.249642)
							(end -0.1778 0.2794)
						)
						(arc
							(start 0.1778 0.2794)
							(mid 0.249642 0.249642)
							(end 0.2794 0.1778)
						)
						(arc
							(start 0.2794 -0.1778)
							(mid 0.249642 -0.249642)
							(end 0.1778 -0.2794)
						)
					)
					(width 0)
					(fill yes)
				)
			)
		)
		(pad "2" smd custom
			(at 0 0.4445 270)
			(size 0.1397 0.1397)
			(layers "F.Cu" "F.Mask" "F.Paste")
			(net "GND")
			(options
				(clearance outline)
				(anchor circle)
			)
			(primitives
				(gr_poly
					(pts
						(arc
							(start -0.1778 -0.2794)
							(mid -0.249642 -0.249642)
							(end -0.2794 -0.1778)
						)
						(arc
							(start -0.2794 0.1778)
							(mid -0.249642 0.249642)
							(end -0.1778 0.2794)
						)
						(arc
							(start 0.1778 0.2794)
							(mid 0.249642 0.249642)
							(end 0.2794 0.1778)
						)
						(arc
							(start 0.2794 -0.1778)
							(mid 0.249642 -0.249642)
							(end 0.1778 -0.2794)
						)
					)
					(width 0)
					(fill yes)
				)
			)
		)
	)
	(footprint ""
		(layer "F.Cu")
		(at 398.907 -243.586 180)
		(property "Reference" "R294"
			(at 0 0 180)
			(layer "F.SilkS")
			(hide yes)
			(effects
				(font
					(size 1.27 1.27)
				)
			)
		)
		(property "Value" "0R2J-2-GP"
			(at 0.064008 -3.993896 180)
			(unlocked yes)
			(layer "F.Fab")
			(hide yes)
			(effects
				(font
					(size 1.016 1.016)
					(thickness 0.1524)
				)
			)
		)
		(property "Device Type" "R402H16"
			(at 0.064008 -5.517896 180)
			(unlocked yes)
			(layer "F.Fab")
			(hide yes)
			(effects
				(font
					(size 1.016 1.016)
					(thickness 0.1524)
				)
			)
		)
		(duplicate_pad_numbers_are_jumpers no)
		(fp_line
			(start 0.508 -0.9398)
			(end -0.508 -0.9398)
			(stroke
				(width 0.1524)
				(type default)
			)
			(layer "F.SilkS")
		)
		(fp_line
			(start -0.508 -0.9398)
			(end -0.508 0.9398)
			(stroke
				(width 0.1524)
				(type default)
			)
			(layer "F.SilkS")
		)
		(fp_rect
			(start -0.508 0.9398)
			(end 0.508 -0.9398)
			(stroke
				(width 0)
				(type default)
			)
			(fill no)
			(layer "F.CrtYd")
		)
		(fp_rect
			(start -0.508 0.9398)
			(end 0.508 -0.9398)
			(stroke
				(width 0)
				(type default)
			)
			(fill no)
			(layer "F.Fab")
		)
		(pad "1" smd custom
			(at 0 -0.4445 180)
			(size 0.1397 0.1397)
			(layers "F.Cu" "F.Mask" "F.Paste")
			(net "DRIVE_B_8_PWR")
			(options
				(clearance outline)
				(anchor circle)
			)
			(primitives
				(gr_poly
					(pts
						(arc
							(start -0.1778 -0.2794)
							(mid -0.249642 -0.249642)
							(end -0.2794 -0.1778)
						)
						(arc
							(start -0.2794 0.1778)
							(mid -0.249642 0.249642)
							(end -0.1778 0.2794)
						)
						(arc
							(start 0.1778 0.2794)
							(mid 0.249642 0.249642)
							(end 0.2794 0.1778)
						)
						(arc
							(start 0.2794 -0.1778)
							(mid 0.249642 -0.249642)
							(end 0.1778 -0.2794)
						)
					)
					(width 0)
					(fill yes)
				)
			)
		)
		(pad "2" smd custom
			(at 0 0.4445 180)
			(size 0.1397 0.1397)
			(layers "F.Cu" "F.Mask" "F.Paste")
			(net "SW_PWR_R_HDD8")
			(options
				(clearance outline)
				(anchor circle)
			)
			(primitives
				(gr_poly
					(pts
						(arc
							(start -0.1778 -0.2794)
							(mid -0.249642 -0.249642)
							(end -0.2794 -0.1778)
						)
						(arc
							(start -0.2794 0.1778)
							(mid -0.249642 0.249642)
							(end -0.1778 0.2794)
						)
						(arc
							(start 0.1778 0.2794)
							(mid 0.249642 0.249642)
							(end 0.2794 0.1778)
						)
						(arc
							(start 0.2794 -0.1778)
							(mid 0.249642 -0.249642)
							(end 0.1778 -0.2794)
						)
					)
					(width 0)
					(fill yes)
				)
			)
		)
	)
	(footprint ""
		(layer "F.Cu")
		(at 254.537972 -372.32971 180)
		(property "Reference" "C556"
			(at 0 0 180)
			(layer "F.SilkS")
			(hide yes)
			(effects
				(font
					(size 1.27 1.27)
				)
			)
		)
		(property "Value" "SCD1U16V2KX-3GP"
			(at 1.1811 -2.7051 180)
			(unlocked yes)
			(layer "F.Fab")
			(hide yes)
			(effects
				(font
					(size 1.016 1.016)
					(thickness 0.1524)
				)
			)
		)
		(property "Device Type" "C402H22"
			(at 1.1811 -4.2291 180)
			(unlocked yes)
			(layer "F.Fab")
			(hide yes)
			(effects
				(font
					(size 1.016 1.016)
					(thickness 0.1524)
				)
			)
		)
		(duplicate_pad_numbers_are_jumpers no)
		(fp_rect
			(start -0.4318 0.9525)
			(end 0.4318 -0.9525)
			(stroke
				(width 0)
				(type default)
			)
			(fill no)
			(layer "F.CrtYd")
		)
		(fp_rect
			(start -0.4318 0.9525)
			(end 0.4318 -0.9525)
			(stroke
				(width 0)
				(type default)
			)
			(fill no)
			(layer "F.Fab")
		)
		(pad "1" smd custom
			(at 0 -0.4445 180)
			(size 0.1524 0.1524)
			(layers "F.Cu" "F.Mask" "F.Paste")
			(net "MB3_CM_VOUT_R")
			(options
				(clearance outline)
				(anchor circle)
			)
			(primitives
				(gr_poly
					(pts
						(arc
							(start 0.3048 -0.2032)
							(mid 0.275042 -0.275042)
							(end 0.2032 -0.3048)
						)
						(arc
							(start -0.2032 -0.3048)
							(mid -0.275042 -0.275042)
							(end -0.3048 -0.2032)
						)
						(arc
							(start -0.3048 0.2032)
							(mid -0.275042 0.275042)
							(end -0.2032 0.3048)
						)
						(arc
							(start 0.2032 0.3048)
							(mid 0.275042 0.275042)
							(end 0.3048 0.2032)
						)
					)
					(width 0)
					(fill yes)
				)
			)
		)
		(pad "2" smd custom
			(at 0 0.4445 180)
			(size 0.1524 0.1524)
			(layers "F.Cu" "F.Mask" "F.Paste")
			(net "AGND_CURRENT_DPB")
			(options
				(clearance outline)
				(anchor circle)
			)
			(primitives
				(gr_poly
					(pts
						(arc
							(start 0.3048 -0.2032)
							(mid 0.275042 -0.275042)
							(end 0.2032 -0.3048)
						)
						(arc
							(start -0.2032 -0.3048)
							(mid -0.275042 -0.275042)
							(end -0.3048 -0.2032)
						)
						(arc
							(start -0.3048 0.2032)
							(mid -0.275042 0.275042)
							(end -0.2032 0.3048)
						)
						(arc
							(start 0.2032 0.3048)
							(mid 0.275042 0.275042)
							(end 0.3048 0.2032)
						)
					)
					(width 0)
					(fill yes)
				)
			)
		)
	)
	(footprint ""
		(layer "F.Cu")
		(at 261.212076 -198.496682)
		(property "Reference" "TC2"
			(at 0 0 0)
			(layer "F.SilkS")
			(hide yes)
			(effects
				(font
					(size 1.27 1.27)
				)
			)
		)
		(property "Value" "SE270U16VM-8-GP"
			(at -4.5974 -2.54 0)
			(unlocked yes)
			(layer "F.Fab")
			(hide yes)
			(effects
				(font
					(size 1.016 1.016)
					(thickness 0.1524)
				)
			)
		)
		(property "Device Type" "SE361416H394"
			(at -4.5974 -4.064 0)
			(unlocked yes)
			(layer "F.Fab")
			(hide yes)
			(effects
				(font
					(size 1.016 1.016)
					(thickness 0.1524)
				)
			)
		)
		(duplicate_pad_numbers_are_jumpers no)
		(fp_line
			(start -3.556 -3.4163)
			(end -2.3622 -4.6101)
			(stroke
				(width 0.1524)
				(type default)
			)
			(layer "F.SilkS")
		)
		(fp_line
			(start -3.556 4.6101)
			(end -3.556 -3.4163)
			(stroke
				(width 0.1524)
				(type default)
			)
			(layer "F.SilkS")
		)
		(fp_line
			(start -2.3622 -4.6101)
			(end 2.3622 -4.6101)
			(stroke
				(width 0.1524)
				(type default)
			)
			(layer "F.SilkS")
		)
		(fp_line
			(start 2.3622 -4.6101)
			(end 3.556 -3.4163)
			(stroke
				(width 0.1524)
				(type default)
			)
			(layer "F.SilkS")
		)
		(fp_line
			(start 3.556 -3.4163)
			(end 3.556 4.6101)
			(stroke
				(width 0.1524)
				(type default)
			)
			(layer "F.SilkS")
		)
		(fp_line
			(start 3.556 4.6101)
			(end -3.556 4.6101)
			(stroke
				(width 0.1524)
				(type default)
			)
			(layer "F.SilkS")
		)
		(fp_rect
			(start -3.302 3.6449)
			(end 3.302 -3.6449)
			(stroke
				(width 0)
				(type default)
			)
			(fill no)
			(layer "F.CrtYd")
		)
		(fp_poly
			(pts
				(xy 3.81 4.6863) (xy 3.81 -3.4925) (xy 3.302 -3.4925) (xy 3.302 3.6449) (xy -3.302 3.6449) (xy -3.302 -3.6449)
				(xy 3.302 -3.6449) (xy 3.302 -3.5052) (xy 3.81 -3.5052) (xy 3.81 -4.6863) (xy -3.81 -4.6863) (xy -3.81 4.6863)
			)
			(stroke
				(width 0)
				(type default)
			)
			(fill no)
			(layer "F.CrtYd")
		)
		(fp_rect
			(start -3.81 4.6863)
			(end 3.81 -4.6863)
			(stroke
				(width 0)
				(type default)
			)
			(fill no)
			(layer "F.Fab")
		)
		(pad "1" smd rect
			(at 0 -2.574036)
			(size 1.4224 3.556)
			(layers "F.Cu" "F.Mask" "F.Paste")
			(net "P12V_B")
		)
		(pad "2" smd rect
			(at 0 2.574036)
			(size 1.4224 3.556)
			(layers "F.Cu" "F.Mask" "F.Paste")
			(net "GND")
		)
	)
	(footprint ""
		(layer "F.Cu")
		(at 420.243 -372.11 90)
		(property "Reference" "R954"
			(at 0 0 90)
			(layer "F.SilkS")
			(hide yes)
			(effects
				(font
					(size 1.27 1.27)
				)
			)
		)
		(property "Value" "100KR2F-L1-GP"
			(at 0.064008 -3.993896 90)
			(unlocked yes)
			(layer "F.Fab")
			(hide yes)
			(effects
				(font
					(size 1.016 1.016)
					(thickness 0.1524)
				)
			)
		)
		(property "Device Type" "R402H16"
			(at 0.064008 -5.517896 90)
			(unlocked yes)
			(layer "F.Fab")
			(hide yes)
			(effects
				(font
					(size 1.016 1.016)
					(thickness 0.1524)
				)
			)
		)
		(duplicate_pad_numbers_are_jumpers no)
		(fp_line
			(start 0.508 -0.9398)
			(end -0.508 -0.9398)
			(stroke
				(width 0.1524)
				(type default)
			)
			(layer "F.SilkS")
		)
		(fp_line
			(start -0.508 -0.9398)
			(end -0.508 0.9398)
			(stroke
				(width 0.1524)
				(type default)
			)
			(layer "F.SilkS")
		)
		(fp_rect
			(start -0.508 0.9398)
			(end 0.508 -0.9398)
			(stroke
				(width 0)
				(type default)
			)
			(fill no)
			(layer "F.CrtYd")
		)
		(fp_rect
			(start -0.508 0.9398)
			(end 0.508 -0.9398)
			(stroke
				(width 0)
				(type default)
			)
			(fill no)
			(layer "F.Fab")
		)
		(pad "1" smd custom
			(at 0 -0.4445 90)
			(size 0.1397 0.1397)
			(layers "F.Cu" "F.Mask" "F.Paste")
			(net "P3V3_IN")
			(options
				(clearance outline)
				(anchor circle)
			)
			(primitives
				(gr_poly
					(pts
						(arc
							(start -0.1778 -0.2794)
							(mid -0.249642 -0.249642)
							(end -0.2794 -0.1778)
						)
						(arc
							(start -0.2794 0.1778)
							(mid -0.249642 0.249642)
							(end -0.1778 0.2794)
						)
						(arc
							(start 0.1778 0.2794)
							(mid 0.249642 0.249642)
							(end 0.2794 0.1778)
						)
						(arc
							(start 0.2794 -0.1778)
							(mid 0.249642 -0.249642)
							(end 0.1778 -0.2794)
						)
					)
					(width 0)
					(fill yes)
				)
			)
		)
		(pad "2" smd custom
			(at 0 0.4445 90)
			(size 0.1397 0.1397)
			(layers "F.Cu" "F.Mask" "F.Paste")
			(net "FAN_3_INS_N")
			(options
				(clearance outline)
				(anchor circle)
			)
			(primitives
				(gr_poly
					(pts
						(arc
							(start -0.1778 -0.2794)
							(mid -0.249642 -0.249642)
							(end -0.2794 -0.1778)
						)
						(arc
							(start -0.2794 0.1778)
							(mid -0.249642 0.249642)
							(end -0.1778 0.2794)
						)
						(arc
							(start 0.1778 0.2794)
							(mid 0.249642 0.249642)
							(end 0.2794 0.1778)
						)
						(arc
							(start 0.2794 -0.1778)
							(mid 0.249642 -0.249642)
							(end 0.1778 -0.2794)
						)
					)
					(width 0)
					(fill yes)
				)
			)
		)
	)
	(footprint ""
		(layer "F.Cu")
		(at 86.0806 -18.4404 -90)
		(property "Reference" "R676"
			(at 0 0 270)
			(layer "F.SilkS")
			(hide yes)
			(effects
				(font
					(size 1.27 1.27)
				)
			)
		)
		(property "Value" "1KR2F-3-GP"
			(at 0.064008 -3.993896 270)
			(unlocked yes)
			(layer "F.Fab")
			(hide yes)
			(effects
				(font
					(size 1.016 1.016)
					(thickness 0.1524)
				)
			)
		)
		(property "Device Type" "R402H16"
			(at 0.064008 -5.517896 270)
			(unlocked yes)
			(layer "F.Fab")
			(hide yes)
			(effects
				(font
					(size 1.016 1.016)
					(thickness 0.1524)
				)
			)
		)
		(duplicate_pad_numbers_are_jumpers no)
		(fp_line
			(start -0.508 -0.9398)
			(end -0.508 0.9398)
			(stroke
				(width 0.1524)
				(type default)
			)
			(layer "F.SilkS")
		)
		(fp_line
			(start 0.508 -0.9398)
			(end -0.508 -0.9398)
			(stroke
				(width 0.1524)
				(type default)
			)
			(layer "F.SilkS")
		)
		(fp_rect
			(start -0.508 0.9398)
			(end 0.508 -0.9398)
			(stroke
				(width 0)
				(type default)
			)
			(fill no)
			(layer "F.CrtYd")
		)
		(fp_rect
			(start -0.508 0.9398)
			(end 0.508 -0.9398)
			(stroke
				(width 0)
				(type default)
			)
			(fill no)
			(layer "F.Fab")
		)
		(pad "1" smd custom
			(at 0 -0.4445 270)
			(size 0.1397 0.1397)
			(layers "F.Cu" "F.Mask" "F.Paste")
			(net "P3V3_STBY_B")
			(options
				(clearance outline)
				(anchor circle)
			)
			(primitives
				(gr_poly
					(pts
						(arc
							(start -0.1778 -0.2794)
							(mid -0.249642 -0.249642)
							(end -0.2794 -0.1778)
						)
						(arc
							(start -0.2794 0.1778)
							(mid -0.249642 0.249642)
							(end -0.1778 0.2794)
						)
						(arc
							(start 0.1778 0.2794)
							(mid 0.249642 0.249642)
							(end 0.2794 0.1778)
						)
						(arc
							(start 0.2794 -0.1778)
							(mid 0.249642 -0.249642)
							(end 0.1778 -0.2794)
						)
					)
					(width 0)
					(fill yes)
				)
			)
		)
		(pad "2" smd custom
			(at 0 0.4445 270)
			(size 0.1397 0.1397)
			(layers "F.Cu" "F.Mask" "F.Paste")
			(net "SW_PWR_R_HDD26")
			(options
				(clearance outline)
				(anchor circle)
			)
			(primitives
				(gr_poly
					(pts
						(arc
							(start -0.1778 -0.2794)
							(mid -0.249642 -0.249642)
							(end -0.2794 -0.1778)
						)
						(arc
							(start -0.2794 0.1778)
							(mid -0.249642 0.249642)
							(end -0.1778 0.2794)
						)
						(arc
							(start 0.1778 0.2794)
							(mid 0.249642 0.249642)
							(end 0.2794 0.1778)
						)
						(arc
							(start 0.2794 -0.1778)
							(mid 0.249642 -0.249642)
							(end 0.1778 -0.2794)
						)
					)
					(width 0)
					(fill yes)
				)
			)
		)
	)
)
